#ISCELL
  mstr_symbols intel_corp_bpage *
  *
#CELL
  mstr_u_proc lbg_core_qat_ext_d *
  page123_i13
#ISCELL
  mstr_symbols gnd *
  page123_i14
#ISCELL
  mstr_symbols gnd *
  page123_i15
#ISCELL
  mstr_symbols pvnn_pch_stby *
  page123_i20
#CELL
  mstr_u_proc lbg_core_qat_ext_d *
  page123_i21
#ISCELL
  mstr_standard offpage *
  page123_i22
#ISCELL
  mstr_standard offpage *
  page123_i23
#ISCELL
  mstr_symbols pvnn_pch_stby *
  page123_i24
#ISCELL
  mstr_symbols p1v05_pch_stby *
  page123_i25
